(kicad_pcb
	(version 20260206)
	(generator "pcbnew")
	(generator_version "10.0")
	(general
		(thickness 1.6)
		(legacy_teardrops no)
	)
	(paper "A4")
	(title_block
		(title "04192023_DAF0TMB3IC0_F0TG_MB_C_brd_V02_OCP.brd")
		(comment 1 "Grand Teton / footprints 5203-5209 of 8354")
	)
	(layers
		(0 "F.Cu" signal "TOP")
		(4 "In1.Cu" signal "GND")
		(6 "In2.Cu" signal "IN1")
		(8 "In3.Cu" signal "GND1")
		(10 "In4.Cu" signal "IN2")
		(12 "In5.Cu" signal "GND2")
		(14 "In6.Cu" signal "IN3")
		(16 "In7.Cu" signal "GND3")
		(18 "In8.Cu" signal "VCC")
		(20 "In9.Cu" signal "VCC1")
		(22 "In10.Cu" signal "GND4")
		(24 "In11.Cu" signal "IN4")
		(26 "In12.Cu" signal "GND5")
		(28 "In13.Cu" signal "IN5")
		(30 "In14.Cu" signal "GND6")
		(32 "In15.Cu" signal "IN6")
		(34 "In16.Cu" signal "GND7")
		(2 "B.Cu" signal "BOTTOM")
		(9 "F.Adhes" user "F.Adhesive")
		(11 "B.Adhes" user "B.Adhesive")
		(13 "F.Paste" user "Package Geometry/Pastemask Top")
		(15 "B.Paste" user "Package Geometry/Pastemask Bottom")
		(5 "F.SilkS" user "Ref Des/Silkscreen Top")
		(7 "B.SilkS" user "Ref Des/Silkscreen Bottom")
		(1 "F.Mask" user "Board Geometry/Soldermask Top")
		(3 "B.Mask" user "Board Geometry/Soldermask Bottom")
		(17 "Dwgs.User" user "User.Drawings")
		(19 "Cmts.User" user "User.Comments")
		(21 "Eco1.User" user "User.Eco1")
		(23 "Eco2.User" user "User.Eco2")
		(25 "Edge.Cuts" user "Board Geometry/Outline")
		(27 "Margin" user)
		(31 "F.CrtYd" user "Package Geometry/Place Bound Top")
		(29 "B.CrtYd" user "Package Geometry/Place Bound Bottom")
		(35 "F.Fab" user "Ref Des/Assembly Top")
		(33 "B.Fab" user "Ref Des/Assembly Bottom")
	)
	(footprint ""
		(layer "B.Cu")
		(at 378.449078 -356.362508 180)
		(property "Reference" ""
			(at 0 0 0)
			(layer "B.SilkS")
			(hide yes)
			(effects
				(font
					(size 1.27 1.27)
				)
				(justify mirror)
			)
		)
		(property "Value" ""
			(at 0 0 0)
			(layer "B.Fab")
			(effects
				(font
					(size 1.27 1.27)
				)
				(justify mirror)
			)
		)
		(duplicate_pad_numbers_are_jumpers no)
		(pad "1" smd circle
			(at 0 0)
			(size 0.9906 0.9906)
			(layers "B.Cu" "B.Mask" "B.Paste")
			(net "Net_2233")
		)
		(zone
			(layer "B.Cu")
			(hatch none 0.5)
			(connect_pads
				(clearance 0)
			)
			(min_thickness 0.25)
			(keepout
				(tracks not_allowed)
				(vias allowed)
				(pads allowed)
				(copperpour not_allowed)
				(footprints allowed)
			)
			(placement
				(enabled no)
				(sheetname "")
			)
			(fill
				(thermal_gap 0.5)
				(thermal_bridge_width 0.5)
				(island_removal_mode 0)
			)
			(polygon
				(pts
					(arc
						(start 380.074678 -356.362508)
						(mid 376.823478 -356.362508)
						(end 380.074678 -356.362508)
					)
				)
			)
		)
	)
	(footprint ""
		(layer "B.Cu")
		(at 439.029602 -421.37711)
		(property "Reference" "PR883"
			(at 0 0 0)
			(layer "B.SilkS")
			(hide yes)
			(effects
				(font
					(size 1.27 1.27)
				)
				(justify mirror)
			)
		)
		(property "Value" ""
			(at 0 0 0)
			(layer "B.Fab")
			(effects
				(font
					(size 1.27 1.27)
				)
				(justify mirror)
			)
		)
		(duplicate_pad_numbers_are_jumpers no)
		(fp_line
			(start -0.7874 -0.4064)
			(end -0.7874 0.4064)
			(stroke
				(width 0.1524)
				(type default)
			)
			(layer "B.SilkS")
		)
		(fp_line
			(start -0.7874 0.4064)
			(end 0.7874 0.4064)
			(stroke
				(width 0.1524)
				(type default)
			)
			(layer "B.SilkS")
		)
		(fp_line
			(start 0.7874 -0.4064)
			(end -0.7874 -0.4064)
			(stroke
				(width 0.1524)
				(type default)
			)
			(layer "B.SilkS")
		)
		(fp_line
			(start 0.7874 0.4064)
			(end 0.7874 -0.4064)
			(stroke
				(width 0.1524)
				(type default)
			)
			(layer "B.SilkS")
		)
		(fp_line
			(start -0.67945 -0.3048)
			(end -0.67945 0.3048)
			(stroke
				(width 0.1)
				(type default)
			)
			(layer "B.Fab")
		)
		(fp_line
			(start -0.67945 0.3048)
			(end -0.120396 0.3048)
			(stroke
				(width 0.1)
				(type default)
			)
			(layer "B.Fab")
		)
		(fp_line
			(start -0.12065 -0.3048)
			(end -0.67945 -0.3048)
			(stroke
				(width 0.1)
				(type default)
			)
			(layer "B.Fab")
		)
		(fp_line
			(start -0.12065 -0.2794)
			(end -0.12065 -0.3048)
			(stroke
				(width 0.1)
				(type default)
			)
			(layer "B.Fab")
		)
		(fp_line
			(start -0.120396 0.2794)
			(end 0.12065 0.2794)
			(stroke
				(width 0.1)
				(type default)
			)
			(layer "B.Fab")
		)
		(fp_line
			(start -0.120396 0.3048)
			(end -0.120396 0.2794)
			(stroke
				(width 0.1)
				(type default)
			)
			(layer "B.Fab")
		)
		(fp_line
			(start 0.12065 -0.305054)
			(end 0.12065 -0.2794)
			(stroke
				(width 0.1)
				(type default)
			)
			(layer "B.Fab")
		)
		(fp_line
			(start 0.12065 -0.2794)
			(end -0.12065 -0.2794)
			(stroke
				(width 0.1)
				(type default)
			)
			(layer "B.Fab")
		)
		(fp_line
			(start 0.12065 0.2794)
			(end 0.12065 0.3048)
			(stroke
				(width 0.1)
				(type default)
			)
			(layer "B.Fab")
		)
		(fp_line
			(start 0.12065 0.3048)
			(end 0.67945 0.3048)
			(stroke
				(width 0.1)
				(type default)
			)
			(layer "B.Fab")
		)
		(fp_line
			(start 0.67945 -0.305054)
			(end 0.12065 -0.305054)
			(stroke
				(width 0.1)
				(type default)
			)
			(layer "B.Fab")
		)
		(fp_line
			(start 0.67945 0.3048)
			(end 0.67945 -0.305054)
			(stroke
				(width 0.1)
				(type default)
			)
			(layer "B.Fab")
		)
		(pad "1" smd circle
			(at 0.40005 0 180)
			(size 0 0)
			(layers "B.Cu" "B.Mask" "B.Paste")
			(net "TP_P0V9_RETIMER_CPU0_SVID_ALERT_N")
		)
		(pad "2" smd circle
			(at -0.40005 0 180)
			(size 0 0)
			(layers "B.Cu" "B.Mask" "B.Paste")
			(net "GND")
		)
	)
	(footprint ""
		(layer "B.Cu")
		(at 187.071 -422.402)
		(property "Reference" "C8014"
			(at 0 0 0)
			(layer "B.SilkS")
			(hide yes)
			(effects
				(font
					(size 1.27 1.27)
				)
				(justify mirror)
			)
		)
		(property "Value" ""
			(at 0 0 0)
			(layer "B.Fab")
			(effects
				(font
					(size 1.27 1.27)
				)
				(justify mirror)
			)
		)
		(duplicate_pad_numbers_are_jumpers no)
		(fp_line
			(start -0.7874 -0.4064)
			(end -0.7874 0.4064)
			(stroke
				(width 0.1524)
				(type default)
			)
			(layer "B.SilkS")
		)
		(fp_line
			(start -0.7874 0.4064)
			(end 0.7874 0.4064)
			(stroke
				(width 0.1524)
				(type default)
			)
			(layer "B.SilkS")
		)
		(fp_line
			(start 0.7874 -0.4064)
			(end -0.7874 -0.4064)
			(stroke
				(width 0.1524)
				(type default)
			)
			(layer "B.SilkS")
		)
		(fp_line
			(start 0.7874 0.4064)
			(end 0.7874 -0.4064)
			(stroke
				(width 0.1524)
				(type default)
			)
			(layer "B.SilkS")
		)
		(fp_line
			(start -0.67945 -0.3048)
			(end -0.67945 0.3048)
			(stroke
				(width 0.1)
				(type default)
			)
			(layer "B.Fab")
		)
		(fp_line
			(start -0.67945 0.3048)
			(end -0.120396 0.3048)
			(stroke
				(width 0.1)
				(type default)
			)
			(layer "B.Fab")
		)
		(fp_line
			(start -0.12065 -0.3048)
			(end -0.67945 -0.3048)
			(stroke
				(width 0.1)
				(type default)
			)
			(layer "B.Fab")
		)
		(fp_line
			(start -0.12065 -0.2794)
			(end -0.12065 -0.3048)
			(stroke
				(width 0.1)
				(type default)
			)
			(layer "B.Fab")
		)
		(fp_line
			(start -0.120396 0.2794)
			(end 0.12065 0.2794)
			(stroke
				(width 0.1)
				(type default)
			)
			(layer "B.Fab")
		)
		(fp_line
			(start -0.120396 0.3048)
			(end -0.120396 0.2794)
			(stroke
				(width 0.1)
				(type default)
			)
			(layer "B.Fab")
		)
		(fp_line
			(start 0.12065 -0.305054)
			(end 0.12065 -0.2794)
			(stroke
				(width 0.1)
				(type default)
			)
			(layer "B.Fab")
		)
		(fp_line
			(start 0.12065 -0.2794)
			(end -0.12065 -0.2794)
			(stroke
				(width 0.1)
				(type default)
			)
			(layer "B.Fab")
		)
		(fp_line
			(start 0.12065 0.2794)
			(end 0.12065 0.3048)
			(stroke
				(width 0.1)
				(type default)
			)
			(layer "B.Fab")
		)
		(fp_line
			(start 0.12065 0.3048)
			(end 0.67945 0.3048)
			(stroke
				(width 0.1)
				(type default)
			)
			(layer "B.Fab")
		)
		(fp_line
			(start 0.67945 -0.305054)
			(end 0.12065 -0.305054)
			(stroke
				(width 0.1)
				(type default)
			)
			(layer "B.Fab")
		)
		(fp_line
			(start 0.67945 0.3048)
			(end 0.67945 -0.305054)
			(stroke
				(width 0.1)
				(type default)
			)
			(layer "B.Fab")
		)
		(pad "1" smd circle
			(at 0.40005 0 180)
			(size 0 0)
			(layers "B.Cu" "B.Mask" "B.Paste")
			(net "OC_P2V5_COMP")
		)
		(pad "2" smd circle
			(at -0.40005 0 180)
			(size 0 0)
			(layers "B.Cu" "B.Mask" "B.Paste")
			(net "GND")
		)
	)
	(footprint ""
		(layer "B.Cu")
		(at 165.419532 -435.13248 -90)
		(property "Reference" "R4573"
			(at 0 0 90)
			(layer "B.SilkS")
			(hide yes)
			(effects
				(font
					(size 1.27 1.27)
				)
				(justify mirror)
			)
		)
		(property "Value" ""
			(at 0 0 90)
			(layer "B.Fab")
			(effects
				(font
					(size 1.27 1.27)
				)
				(justify mirror)
			)
		)
		(duplicate_pad_numbers_are_jumpers no)
		(fp_line
			(start -0.7874 0.4064)
			(end 0.7874 0.4064)
			(stroke
				(width 0.1524)
				(type default)
			)
			(layer "B.SilkS")
		)
		(fp_line
			(start 0.7874 0.4064)
			(end 0.7874 -0.4064)
			(stroke
				(width 0.1524)
				(type default)
			)
			(layer "B.SilkS")
		)
		(fp_line
			(start -0.7874 -0.4064)
			(end -0.7874 0.4064)
			(stroke
				(width 0.1524)
				(type default)
			)
			(layer "B.SilkS")
		)
		(fp_line
			(start 0.7874 -0.4064)
			(end -0.7874 -0.4064)
			(stroke
				(width 0.1524)
				(type default)
			)
			(layer "B.SilkS")
		)
		(fp_line
			(start -0.67945 0.3048)
			(end -0.120396 0.3048)
			(stroke
				(width 0.1)
				(type default)
			)
			(layer "B.Fab")
		)
		(fp_line
			(start -0.120396 0.3048)
			(end -0.120396 0.2794)
			(stroke
				(width 0.1)
				(type default)
			)
			(layer "B.Fab")
		)
		(fp_line
			(start 0.12065 0.3048)
			(end 0.67945 0.3048)
			(stroke
				(width 0.1)
				(type default)
			)
			(layer "B.Fab")
		)
		(fp_line
			(start 0.67945 0.3048)
			(end 0.67945 -0.305054)
			(stroke
				(width 0.1)
				(type default)
			)
			(layer "B.Fab")
		)
		(fp_line
			(start -0.120396 0.2794)
			(end 0.12065 0.2794)
			(stroke
				(width 0.1)
				(type default)
			)
			(layer "B.Fab")
		)
		(fp_line
			(start 0.12065 0.2794)
			(end 0.12065 0.3048)
			(stroke
				(width 0.1)
				(type default)
			)
			(layer "B.Fab")
		)
		(fp_line
			(start -0.12065 -0.2794)
			(end -0.12065 -0.3048)
			(stroke
				(width 0.1)
				(type default)
			)
			(layer "B.Fab")
		)
		(fp_line
			(start 0.12065 -0.2794)
			(end -0.12065 -0.2794)
			(stroke
				(width 0.1)
				(type default)
			)
			(layer "B.Fab")
		)
		(fp_line
			(start -0.67945 -0.3048)
			(end -0.67945 0.3048)
			(stroke
				(width 0.1)
				(type default)
			)
			(layer "B.Fab")
		)
		(fp_line
			(start -0.12065 -0.3048)
			(end -0.67945 -0.3048)
			(stroke
				(width 0.1)
				(type default)
			)
			(layer "B.Fab")
		)
		(fp_line
			(start 0.12065 -0.305054)
			(end 0.12065 -0.2794)
			(stroke
				(width 0.1)
				(type default)
			)
			(layer "B.Fab")
		)
		(fp_line
			(start 0.67945 -0.305054)
			(end 0.12065 -0.305054)
			(stroke
				(width 0.1)
				(type default)
			)
			(layer "B.Fab")
		)
		(pad "1" smd circle
			(at 0.40005 0 90)
			(size 0 0)
			(layers "B.Cu" "B.Mask" "B.Paste")
			(net "PRSNT_CABLE_GPU_B3_N")
		)
		(pad "2" smd circle
			(at -0.40005 0 90)
			(size 0 0)
			(layers "B.Cu" "B.Mask" "B.Paste")
			(net "PRSNT_CABLE_GPU_B3_ISO_N")
		)
	)
	(footprint ""
		(layer "B.Cu")
		(at 278.189182 -244.08511 180)
		(property "Reference" "R379"
			(at 0 0 0)
			(layer "B.SilkS")
			(hide yes)
			(effects
				(font
					(size 1.27 1.27)
				)
				(justify mirror)
			)
		)
		(property "Value" ""
			(at 0 0 0)
			(layer "B.Fab")
			(effects
				(font
					(size 1.27 1.27)
				)
				(justify mirror)
			)
		)
		(duplicate_pad_numbers_are_jumpers no)
		(fp_line
			(start 0.7874 0.4064)
			(end 0.7874 -0.4064)
			(stroke
				(width 0.1524)
				(type default)
			)
			(layer "B.SilkS")
		)
		(fp_line
			(start 0.7874 -0.4064)
			(end -0.7874 -0.4064)
			(stroke
				(width 0.1524)
				(type default)
			)
			(layer "B.SilkS")
		)
		(fp_line
			(start -0.7874 0.4064)
			(end 0.7874 0.4064)
			(stroke
				(width 0.1524)
				(type default)
			)
			(layer "B.SilkS")
		)
		(fp_line
			(start -0.7874 -0.4064)
			(end -0.7874 0.4064)
			(stroke
				(width 0.1524)
				(type default)
			)
			(layer "B.SilkS")
		)
		(fp_line
			(start 0.67945 0.3048)
			(end 0.67945 -0.305054)
			(stroke
				(width 0.1)
				(type default)
			)
			(layer "B.Fab")
		)
		(fp_line
			(start 0.67945 -0.305054)
			(end 0.12065 -0.305054)
			(stroke
				(width 0.1)
				(type default)
			)
			(layer "B.Fab")
		)
		(fp_line
			(start 0.12065 0.3048)
			(end 0.67945 0.3048)
			(stroke
				(width 0.1)
				(type default)
			)
			(layer "B.Fab")
		)
		(fp_line
			(start 0.12065 0.2794)
			(end 0.12065 0.3048)
			(stroke
				(width 0.1)
				(type default)
			)
			(layer "B.Fab")
		)
		(fp_line
			(start 0.12065 -0.2794)
			(end -0.12065 -0.2794)
			(stroke
				(width 0.1)
				(type default)
			)
			(layer "B.Fab")
		)
		(fp_line
			(start 0.12065 -0.305054)
			(end 0.12065 -0.2794)
			(stroke
				(width 0.1)
				(type default)
			)
			(layer "B.Fab")
		)
		(fp_line
			(start -0.120396 0.3048)
			(end -0.120396 0.2794)
			(stroke
				(width 0.1)
				(type default)
			)
			(layer "B.Fab")
		)
		(fp_line
			(start -0.120396 0.2794)
			(end 0.12065 0.2794)
			(stroke
				(width 0.1)
				(type default)
			)
			(layer "B.Fab")
		)
		(fp_line
			(start -0.12065 -0.2794)
			(end -0.12065 -0.3048)
			(stroke
				(width 0.1)
				(type default)
			)
			(layer "B.Fab")
		)
		(fp_line
			(start -0.12065 -0.3048)
			(end -0.67945 -0.3048)
			(stroke
				(width 0.1)
				(type default)
			)
			(layer "B.Fab")
		)
		(fp_line
			(start -0.67945 0.3048)
			(end -0.120396 0.3048)
			(stroke
				(width 0.1)
				(type default)
			)
			(layer "B.Fab")
		)
		(fp_line
			(start -0.67945 -0.3048)
			(end -0.67945 0.3048)
			(stroke
				(width 0.1)
				(type default)
			)
			(layer "B.Fab")
		)
		(pad "1" smd circle
			(at 0.40005 0)
			(size 0 0)
			(layers "B.Cu" "B.Mask" "B.Paste")
			(net "M_E_CPU0_ALERT_N")
		)
		(pad "2" smd circle
			(at -0.40005 0)
			(size 0 0)
			(layers "B.Cu" "B.Mask" "B.Paste")
			(net "M_E_CPU0_ALERT_R_N")
		)
	)
	(footprint ""
		(layer "B.Cu")
		(at 104.521 -424.815)
		(property "Reference" "R8002"
			(at 0 0 0)
			(layer "B.SilkS")
			(hide yes)
			(effects
				(font
					(size 1.27 1.27)
				)
				(justify mirror)
			)
		)
		(property "Value" ""
			(at 0 0 0)
			(layer "B.Fab")
			(effects
				(font
					(size 1.27 1.27)
				)
				(justify mirror)
			)
		)
		(duplicate_pad_numbers_are_jumpers no)
		(fp_line
			(start -0.7874 -0.4064)
			(end -0.7874 0.4064)
			(stroke
				(width 0.1524)
				(type default)
			)
			(layer "B.SilkS")
		)
		(fp_line
			(start -0.7874 0.4064)
			(end 0.7874 0.4064)
			(stroke
				(width 0.1524)
				(type default)
			)
			(layer "B.SilkS")
		)
		(fp_line
			(start 0.7874 -0.4064)
			(end -0.7874 -0.4064)
			(stroke
				(width 0.1524)
				(type default)
			)
			(layer "B.SilkS")
		)
		(fp_line
			(start 0.7874 0.4064)
			(end 0.7874 -0.4064)
			(stroke
				(width 0.1524)
				(type default)
			)
			(layer "B.SilkS")
		)
		(fp_line
			(start -0.67945 -0.3048)
			(end -0.67945 0.3048)
			(stroke
				(width 0.1)
				(type default)
			)
			(layer "B.Fab")
		)
		(fp_line
			(start -0.67945 0.3048)
			(end -0.120396 0.3048)
			(stroke
				(width 0.1)
				(type default)
			)
			(layer "B.Fab")
		)
		(fp_line
			(start -0.12065 -0.3048)
			(end -0.67945 -0.3048)
			(stroke
				(width 0.1)
				(type default)
			)
			(layer "B.Fab")
		)
		(fp_line
			(start -0.12065 -0.2794)
			(end -0.12065 -0.3048)
			(stroke
				(width 0.1)
				(type default)
			)
			(layer "B.Fab")
		)
		(fp_line
			(start -0.120396 0.2794)
			(end 0.12065 0.2794)
			(stroke
				(width 0.1)
				(type default)
			)
			(layer "B.Fab")
		)
		(fp_line
			(start -0.120396 0.3048)
			(end -0.120396 0.2794)
			(stroke
				(width 0.1)
				(type default)
			)
			(layer "B.Fab")
		)
		(fp_line
			(start 0.12065 -0.305054)
			(end 0.12065 -0.2794)
			(stroke
				(width 0.1)
				(type default)
			)
			(layer "B.Fab")
		)
		(fp_line
			(start 0.12065 -0.2794)
			(end -0.12065 -0.2794)
			(stroke
				(width 0.1)
				(type default)
			)
			(layer "B.Fab")
		)
		(fp_line
			(start 0.12065 0.2794)
			(end 0.12065 0.3048)
			(stroke
				(width 0.1)
				(type default)
			)
			(layer "B.Fab")
		)
		(fp_line
			(start 0.12065 0.3048)
			(end 0.67945 0.3048)
			(stroke
				(width 0.1)
				(type default)
			)
			(layer "B.Fab")
		)
		(fp_line
			(start 0.67945 -0.305054)
			(end 0.12065 -0.305054)
			(stroke
				(width 0.1)
				(type default)
			)
			(layer "B.Fab")
		)
		(fp_line
			(start 0.67945 0.3048)
			(end 0.67945 -0.305054)
			(stroke
				(width 0.1)
				(type default)
			)
			(layer "B.Fab")
		)
		(pad "1" smd circle
			(at 0.40005 0 180)
			(size 0 0)
			(layers "B.Cu" "B.Mask" "B.Paste")
			(net "P3V3_AUX")
		)
		(pad "2" smd circle
			(at -0.40005 0 180)
			(size 0 0)
			(layers "B.Cu" "B.Mask" "B.Paste")
			(net "PRSNT_SWB")
		)
	)
	(footprint ""
		(layer "B.Cu")
		(at 398.230344 -145.401538 90)
		(property "Reference" "C9226"
			(at 0 0 90)
			(layer "B.SilkS")
			(hide yes)
			(effects
				(font
					(size 1.27 1.27)
				)
				(justify mirror)
			)
		)
		(property "Value" ""
			(at 0 0 90)
			(layer "B.Fab")
			(effects
				(font
					(size 1.27 1.27)
				)
				(justify mirror)
			)
		)
		(duplicate_pad_numbers_are_jumpers no)
		(fp_line
			(start 0.7874 -0.4064)
			(end -0.7874 -0.4064)
			(stroke
				(width 0.1524)
				(type default)
			)
			(layer "B.SilkS")
		)
		(fp_line
			(start -0.7874 -0.4064)
			(end -0.7874 0.4064)
			(stroke
				(width 0.1524)
				(type default)
			)
			(layer "B.SilkS")
		)
		(fp_line
			(start 0.7874 0.4064)
			(end 0.7874 -0.4064)
			(stroke
				(width 0.1524)
				(type default)
			)
			(layer "B.SilkS")
		)
		(fp_line
			(start -0.7874 0.4064)
			(end 0.7874 0.4064)
			(stroke
				(width 0.1524)
				(type default)
			)
			(layer "B.SilkS")
		)
		(fp_line
			(start 0.67945 -0.305054)
			(end 0.12065 -0.305054)
			(stroke
				(width 0.1)
				(type default)
			)
			(layer "B.Fab")
		)
		(fp_line
			(start 0.12065 -0.305054)
			(end 0.12065 -0.2794)
			(stroke
				(width 0.1)
				(type default)
			)
			(layer "B.Fab")
		)
		(fp_line
			(start -0.12065 -0.3048)
			(end -0.67945 -0.3048)
			(stroke
				(width 0.1)
				(type default)
			)
			(layer "B.Fab")
		)
		(fp_line
			(start -0.67945 -0.3048)
			(end -0.67945 0.3048)
			(stroke
				(width 0.1)
				(type default)
			)
			(layer "B.Fab")
		)
		(fp_line
			(start 0.12065 -0.2794)
			(end -0.12065 -0.2794)
			(stroke
				(width 0.1)
				(type default)
			)
			(layer "B.Fab")
		)
		(fp_line
			(start -0.12065 -0.2794)
			(end -0.12065 -0.3048)
			(stroke
				(width 0.1)
				(type default)
			)
			(layer "B.Fab")
		)
		(fp_line
			(start 0.12065 0.2794)
			(end 0.12065 0.3048)
			(stroke
				(width 0.1)
				(type default)
			)
			(layer "B.Fab")
		)
		(fp_line
			(start -0.120396 0.2794)
			(end 0.12065 0.2794)
			(stroke
				(width 0.1)
				(type default)
			)
			(layer "B.Fab")
		)
		(fp_line
			(start 0.67945 0.3048)
			(end 0.67945 -0.305054)
			(stroke
				(width 0.1)
				(type default)
			)
			(layer "B.Fab")
		)
		(fp_line
			(start 0.12065 0.3048)
			(end 0.67945 0.3048)
			(stroke
				(width 0.1)
				(type default)
			)
			(layer "B.Fab")
		)
		(fp_line
			(start -0.120396 0.3048)
			(end -0.120396 0.2794)
			(stroke
				(width 0.1)
				(type default)
			)
			(layer "B.Fab")
		)
		(fp_line
			(start -0.67945 0.3048)
			(end -0.120396 0.3048)
			(stroke
				(width 0.1)
				(type default)
			)
			(layer "B.Fab")
		)
		(pad "1" smd circle
			(at 0.40005 0 270)
			(size 0 0)
			(layers "B.Cu" "B.Mask" "B.Paste")
			(net "VR_P5V_EN_D_R")
		)
		(pad "2" smd circle
			(at -0.40005 0 270)
			(size 0 0)
			(layers "B.Cu" "B.Mask" "B.Paste")
			(net "GND")
		)
	)
)
